# BASEBOARD_FAB2 (Tioga Pass) — schematic netlist excerpt (pin names and nets, part order shuffled) for the footprints in the layout excerpt that follows; sources: Cadence DE-HDL packaged netlist, KiCad conversion of Wiwynn_Tioga_Pass_MB.brd

R1W42  RES  4.75K 1% CHIP  pkg 0402  page 188 : A = P3V3_STBY ; B = FM_GBE0_LVC3_MOD_ABS
R7P9  RES  42.2 1.0% EMPTY  pkg 0402  page 103 : A = CLK_100M_CPU1_RC_REFCLK1_DP ; B = GND
C3T12  CAP  10UF 16V 10% X6S  pkg 0805  page 231 : A = VR_FET_SW_P12V_STBY_PVPP_ABC ; B = GND

(kicad_pcb
	(version 20260206)
	(generator "pcbnew")
	(generator_version "10.0")
	(general
		(thickness 1.6)
		(legacy_teardrops no)
	)
	(paper "A4")
	(title_block
		(title "Wiwynn_Tioga_Pass_MB.brd")
		(comment 1 "Tioga Pass / footprints 3840-3842 of 4770")
	)
	(layers
		(0 "F.Cu" signal "TOP")
		(4 "In1.Cu" signal "L2GND")
		(6 "In2.Cu" signal "L3")
		(8 "In3.Cu" signal "L4GND")
		(10 "In4.Cu" signal "L5")
		(12 "In5.Cu" signal "L6GND")
		(14 "In6.Cu" signal "L7VCC")
		(16 "In7.Cu" signal "L8VCC")
		(18 "In8.Cu" signal "L9GND")
		(20 "In9.Cu" signal "L10")
		(22 "In10.Cu" signal "L11GND")
		(24 "In11.Cu" signal "L12")
		(26 "In12.Cu" signal "L13GND")
		(2 "B.Cu" signal "BOTTOM")
		(9 "F.Adhes" user "F.Adhesive")
		(11 "B.Adhes" user "B.Adhesive")
		(13 "F.Paste" user "Package Geometry/Pastemask Top")
		(15 "B.Paste" user "Package Geometry/Pastemask Bottom")
		(5 "F.SilkS" user "Ref Des/Silkscreen Top")
		(7 "B.SilkS" user "Ref Des/Silkscreen Bottom")
		(1 "F.Mask" user "Board Geometry/Soldermask Top")
		(3 "B.Mask" user "Board Geometry/Soldermask Bottom")
		(17 "Dwgs.User" user "User.Drawings")
		(19 "Cmts.User" user "User.Comments")
		(21 "Eco1.User" user "User.Eco1")
		(23 "Eco2.User" user "User.Eco2")
		(25 "Edge.Cuts" user "Board Geometry/Outline")
		(27 "Margin" user)
		(31 "F.CrtYd" user "Package Geometry/Place Bound Top")
		(29 "B.CrtYd" user "Package Geometry/Place Bound Bottom")
		(35 "F.Fab" user "Ref Des/Assembly Top")
		(33 "B.Fab" user "Ref Des/Assembly Bottom")
	)
	(footprint ""
		(layer "B.Cu")
		(at 162.7886 -77.978 90)
		(property "Reference" "R7P9"
			(at 0 0 90)
			(layer "B.SilkS")
			(hide yes)
			(effects
				(font
					(size 1.27 1.27)
				)
				(justify mirror)
			)
		)
		(property "Value" ""
			(at 0 0 90)
			(layer "B.Fab")
			(effects
				(font
					(size 1.27 1.27)
				)
				(justify mirror)
			)
		)
		(duplicate_pad_numbers_are_jumpers no)
		(fp_poly
			(pts
				(xy 0.2794 -0.1016) (xy -0.2794 -0.1016) (xy -0.2794 0.9906) (xy 0.2794 0.9906)
			)
			(stroke
				(width 0)
				(type default)
			)
			(fill no)
			(layer "B.CrtYd")
		)
		(fp_line
			(start 0.2794 -0.1016)
			(end 0.2794 0.9906)
			(stroke
				(width 0.1)
				(type default)
			)
			(layer "B.Fab")
		)
		(fp_line
			(start -0.2794 -0.1016)
			(end 0.2794 -0.1016)
			(stroke
				(width 0.1)
				(type default)
			)
			(layer "B.Fab")
		)
		(fp_line
			(start 0.2794 0.9906)
			(end -0.2794 0.9906)
			(stroke
				(width 0.1)
				(type default)
			)
			(layer "B.Fab")
		)
		(fp_line
			(start -0.2794 0.9906)
			(end -0.2794 -0.1016)
			(stroke
				(width 0.1)
				(type default)
			)
			(layer "B.Fab")
		)
		(pad "1" smd rect
			(at 0 0 270)
			(size 0.508 0.508)
			(layers "B.Cu" "B.Mask" "B.Paste")
			(net "CLK_100M_CPU1_RC_REFCLK1_DP")
		)
		(pad "2" smd rect
			(at 0 0.889 270)
			(size 0.508 0.508)
			(layers "B.Cu" "B.Mask" "B.Paste")
			(net "GND")
		)
		(zone
			(layer "B.Cu")
			(hatch none 0.5)
			(connect_pads
				(clearance 0)
			)
			(min_thickness 0.25)
			(keepout
				(tracks allowed)
				(vias not_allowed)
				(pads allowed)
				(copperpour not_allowed)
				(footprints allowed)
			)
			(placement
				(enabled no)
				(sheetname "")
			)
			(fill
				(thermal_gap 0.5)
				(thermal_bridge_width 0.5)
				(island_removal_mode 0)
			)
			(polygon
				(pts
					(xy 163.0426 -78.232) (xy 163.0426 -77.724) (xy 163.4236 -77.724) (xy 163.4236 -78.232)
				)
			)
		)
		(zone
			(layer "B.Cu")
			(hatch none 0.5)
			(connect_pads
				(clearance 0)
			)
			(min_thickness 0.25)
			(keepout
				(tracks not_allowed)
				(vias allowed)
				(pads allowed)
				(copperpour not_allowed)
				(footprints allowed)
			)
			(placement
				(enabled no)
				(sheetname "")
			)
			(fill
				(thermal_gap 0.5)
				(thermal_bridge_width 0.5)
				(island_removal_mode 0)
			)
			(polygon
				(pts
					(xy 163.4236 -78.232) (xy 163.4236 -77.724) (xy 163.0426 -77.724) (xy 163.0426 -78.232)
				)
			)
		)
	)
	(footprint ""
		(layer "B.Cu")
		(at 351.416874 -26.505916 90)
		(property "Reference" "C3T12"
			(at -1.47828 0.78994 180)
			(unlocked yes)
			(layer "B.SilkS")
			(effects
				(font
					(size 0.4064 0.254)
					(thickness 0.1524)
				)
				(justify mirror)
			)
		)
		(property "Value" ""
			(at 0 0 90)
			(layer "B.Fab")
			(effects
				(font
					(size 1.27 1.27)
				)
				(justify mirror)
			)
		)
		(duplicate_pad_numbers_are_jumpers no)
		(fp_poly
			(pts
				(xy 0.7239 -0.2159) (xy -0.7239 -0.2159) (xy -0.7239 1.9939) (xy 0.7239 1.9939)
			)
			(stroke
				(width 0)
				(type default)
			)
			(fill no)
			(layer "B.CrtYd")
		)
		(fp_line
			(start 0.7239 -0.2159)
			(end 0.7239 1.9939)
			(stroke
				(width 0.1)
				(type default)
			)
			(layer "B.Fab")
		)
		(fp_line
			(start -0.7239 -0.2159)
			(end 0.7239 -0.2159)
			(stroke
				(width 0.1)
				(type default)
			)
			(layer "B.Fab")
		)
		(fp_line
			(start 0.7239 1.9939)
			(end -0.7239 1.9939)
			(stroke
				(width 0.1)
				(type default)
			)
			(layer "B.Fab")
		)
		(fp_line
			(start -0.7239 1.9939)
			(end -0.7239 -0.2159)
			(stroke
				(width 0.1)
				(type default)
			)
			(layer "B.Fab")
		)
		(pad "1" smd rect
			(at 0 0 270)
			(size 1.27 1.016)
			(layers "B.Cu" "B.Mask" "B.Paste")
			(net "VR_FET_SW_P12V_STBY_PVPP_ABC")
		)
		(pad "2" smd rect
			(at 0 1.778 270)
			(size 1.27 1.016)
			(layers "B.Cu" "B.Mask" "B.Paste")
			(net "GND")
		)
		(zone
			(layer "B.Cu")
			(hatch none 0.5)
			(connect_pads
				(clearance 0)
			)
			(min_thickness 0.25)
			(keepout
				(tracks not_allowed)
				(vias allowed)
				(pads allowed)
				(copperpour not_allowed)
				(footprints allowed)
			)
			(placement
				(enabled no)
				(sheetname "")
			)
			(fill
				(thermal_gap 0.5)
				(thermal_bridge_width 0.5)
				(island_removal_mode 0)
			)
			(polygon
				(pts
					(xy 351.924874 -27.140916) (xy 351.924874 -25.870916) (xy 352.686874 -25.870916) (xy 352.686874 -27.140916)
				)
			)
		)
	)
	(footprint ""
		(layer "B.Cu")
		(at 446.8876 -61.8236 -90)
		(property "Reference" "R1W42"
			(at 0.8382 -0.67818 270)
			(unlocked yes)
			(layer "B.SilkS")
			(effects
				(font
					(size 0.4064 0.254)
					(thickness 0.1524)
				)
				(justify left mirror)
			)
		)
		(property "Value" ""
			(at 0 0 90)
			(layer "B.Fab")
			(effects
				(font
					(size 1.27 1.27)
				)
				(justify mirror)
			)
		)
		(duplicate_pad_numbers_are_jumpers no)
		(fp_poly
			(pts
				(xy 0.2794 -0.1016) (xy -0.2794 -0.1016) (xy -0.2794 0.9906) (xy 0.2794 0.9906)
			)
			(stroke
				(width 0)
				(type default)
			)
			(fill no)
			(layer "B.CrtYd")
		)
		(fp_line
			(start -0.2794 0.9906)
			(end -0.2794 -0.1016)
			(stroke
				(width 0.1)
				(type default)
			)
			(layer "B.Fab")
		)
		(fp_line
			(start 0.2794 0.9906)
			(end -0.2794 0.9906)
			(stroke
				(width 0.1)
				(type default)
			)
			(layer "B.Fab")
		)
		(fp_line
			(start -0.2794 -0.1016)
			(end 0.2794 -0.1016)
			(stroke
				(width 0.1)
				(type default)
			)
			(layer "B.Fab")
		)
		(fp_line
			(start 0.2794 -0.1016)
			(end 0.2794 0.9906)
			(stroke
				(width 0.1)
				(type default)
			)
			(layer "B.Fab")
		)
		(pad "1" smd rect
			(at 0 0 90)
			(size 0.508 0.508)
			(layers "B.Cu" "B.Mask" "B.Paste")
			(net "P3V3_STBY")
		)
		(pad "2" smd rect
			(at 0 0.889 90)
			(size 0.508 0.508)
			(layers "B.Cu" "B.Mask" "B.Paste")
			(net "FM_GBE0_LVC3_MOD_ABS")
		)
		(zone
			(layer "B.Cu")
			(hatch none 0.5)
			(connect_pads
				(clearance 0)
			)
			(min_thickness 0.25)
			(keepout
				(tracks not_allowed)
				(vias allowed)
				(pads allowed)
				(copperpour not_allowed)
				(footprints allowed)
			)
			(placement
				(enabled no)
				(sheetname "")
			)
			(fill
				(thermal_gap 0.5)
				(thermal_bridge_width 0.5)
				(island_removal_mode 0)
			)
			(polygon
				(pts
					(xy 446.2526 -61.5696) (xy 446.2526 -62.0776) (xy 446.6336 -62.0776) (xy 446.6336 -61.5696)
				)
			)
		)
		(zone
			(layer "B.Cu")
			(hatch none 0.5)
			(connect_pads
				(clearance 0)
			)
			(min_thickness 0.25)
			(keepout
				(tracks allowed)
				(vias not_allowed)
				(pads allowed)
				(copperpour not_allowed)
				(footprints allowed)
			)
			(placement
				(enabled no)
				(sheetname "")
			)
			(fill
				(thermal_gap 0.5)
				(thermal_bridge_width 0.5)
				(island_removal_mode 0)
			)
			(polygon
				(pts
					(xy 446.6336 -61.5696) (xy 446.6336 -62.0776) (xy 446.2526 -62.0776) (xy 446.2526 -61.5696)
				)
			)
		)
	)
)
